# T6G (Grand Teton) — schematic netlist excerpt (pin names and nets, part order shuffled) for the footprints in the layout excerpt that follows; sources: Cadence DE-HDL packaged netlist, KiCad conversion of 04192023_DAF0TMB3IC0_F0TG_MB_C_brd_V02_OCP.brd

R40  Q_RES  0 5% CHIP  pkg 0402LF  page 131 : A = OCP_SFF_ISO_BIF1_EN ; B = OCP_SFF_BIF1_R_N
PC6610  Q_CAP  2.2UF 10V 10% X6S  pkg C0402  page 365 : A = P0V9_RETIMER_CPU1_VCC1 ; B = GND

(kicad_pcb
	(version 20260206)
	(generator "pcbnew")
	(generator_version "10.0")
	(general
		(thickness 1.6)
		(legacy_teardrops no)
	)
	(paper "A4")
	(title_block
		(title "04192023_DAF0TMB3IC0_F0TG_MB_C_brd_V02_OCP.brd")
		(comment 1 "Grand Teton / footprints 4100-4101 of 8354")
	)
	(layers
		(0 "F.Cu" signal "TOP")
		(4 "In1.Cu" signal "GND")
		(6 "In2.Cu" signal "IN1")
		(8 "In3.Cu" signal "GND1")
		(10 "In4.Cu" signal "IN2")
		(12 "In5.Cu" signal "GND2")
		(14 "In6.Cu" signal "IN3")
		(16 "In7.Cu" signal "GND3")
		(18 "In8.Cu" signal "VCC")
		(20 "In9.Cu" signal "VCC1")
		(22 "In10.Cu" signal "GND4")
		(24 "In11.Cu" signal "IN4")
		(26 "In12.Cu" signal "GND5")
		(28 "In13.Cu" signal "IN5")
		(30 "In14.Cu" signal "GND6")
		(32 "In15.Cu" signal "IN6")
		(34 "In16.Cu" signal "GND7")
		(2 "B.Cu" signal "BOTTOM")
		(9 "F.Adhes" user "F.Adhesive")
		(11 "B.Adhes" user "B.Adhesive")
		(13 "F.Paste" user "Package Geometry/Pastemask Top")
		(15 "B.Paste" user "Package Geometry/Pastemask Bottom")
		(5 "F.SilkS" user "Ref Des/Silkscreen Top")
		(7 "B.SilkS" user "Ref Des/Silkscreen Bottom")
		(1 "F.Mask" user "Board Geometry/Soldermask Top")
		(3 "B.Mask" user "Board Geometry/Soldermask Bottom")
		(17 "Dwgs.User" user "User.Drawings")
		(19 "Cmts.User" user "User.Comments")
		(21 "Eco1.User" user "User.Eco1")
		(23 "Eco2.User" user "User.Eco2")
		(25 "Edge.Cuts" user "Board Geometry/Outline")
		(27 "Margin" user)
		(31 "F.CrtYd" user "Package Geometry/Place Bound Top")
		(29 "B.CrtYd" user "Package Geometry/Place Bound Bottom")
		(35 "F.Fab" user "Ref Des/Assembly Top")
		(33 "B.Fab" user "Ref Des/Assembly Bottom")
	)
	(footprint ""
		(layer "F.Cu")
		(at 12.860274 -390.822434 90)
		(property "Reference" "PC6610"
			(at 0 0 90)
			(layer "F.SilkS")
			(hide yes)
			(effects
				(font
					(size 1.27 1.27)
				)
			)
		)
		(property "Value" ""
			(at 0 0 90)
			(layer "F.Fab")
			(effects
				(font
					(size 1.27 1.27)
				)
			)
		)
		(duplicate_pad_numbers_are_jumpers no)
		(fp_line
			(start 0.7874 -0.4064)
			(end 0.7874 -0.185674)
			(stroke
				(width 0.1524)
				(type default)
			)
			(layer "F.SilkS")
		)
		(fp_line
			(start -0.7874 -0.4064)
			(end 0.7874 -0.4064)
			(stroke
				(width 0.1524)
				(type default)
			)
			(layer "F.SilkS")
		)
		(fp_line
			(start 0.540766 0.4064)
			(end -0.7874 0.4064)
			(stroke
				(width 0.1524)
				(type default)
			)
			(layer "F.SilkS")
		)
		(fp_line
			(start -0.7874 0.4064)
			(end -0.7874 -0.4064)
			(stroke
				(width 0.1524)
				(type default)
			)
			(layer "F.SilkS")
		)
		(fp_line
			(start -0.12065 -0.305054)
			(end -0.12065 -0.2794)
			(stroke
				(width 0.1)
				(type default)
			)
			(layer "F.Fab")
		)
		(fp_line
			(start -0.67945 -0.305054)
			(end -0.12065 -0.305054)
			(stroke
				(width 0.1)
				(type default)
			)
			(layer "F.Fab")
		)
		(fp_line
			(start 0.67945 -0.3048)
			(end 0.67945 0.3048)
			(stroke
				(width 0.1)
				(type default)
			)
			(layer "F.Fab")
		)
		(fp_line
			(start 0.12065 -0.3048)
			(end 0.67945 -0.3048)
			(stroke
				(width 0.1)
				(type default)
			)
			(layer "F.Fab")
		)
		(fp_line
			(start 0.12065 -0.2794)
			(end 0.12065 -0.3048)
			(stroke
				(width 0.1)
				(type default)
			)
			(layer "F.Fab")
		)
		(fp_line
			(start -0.12065 -0.2794)
			(end 0.12065 -0.2794)
			(stroke
				(width 0.1)
				(type default)
			)
			(layer "F.Fab")
		)
		(fp_line
			(start 0.120396 0.2794)
			(end -0.12065 0.2794)
			(stroke
				(width 0.1)
				(type default)
			)
			(layer "F.Fab")
		)
		(fp_line
			(start -0.12065 0.2794)
			(end -0.12065 0.3048)
			(stroke
				(width 0.1)
				(type default)
			)
			(layer "F.Fab")
		)
		(fp_line
			(start 0.67945 0.3048)
			(end 0.120396 0.3048)
			(stroke
				(width 0.1)
				(type default)
			)
			(layer "F.Fab")
		)
		(fp_line
			(start 0.120396 0.3048)
			(end 0.120396 0.2794)
			(stroke
				(width 0.1)
				(type default)
			)
			(layer "F.Fab")
		)
		(fp_line
			(start -0.12065 0.3048)
			(end -0.67945 0.3048)
			(stroke
				(width 0.1)
				(type default)
			)
			(layer "F.Fab")
		)
		(fp_line
			(start -0.67945 0.3048)
			(end -0.67945 -0.305054)
			(stroke
				(width 0.1)
				(type default)
			)
			(layer "F.Fab")
		)
		(pad "1" smd circle
			(at -0.40005 0 90)
			(size 0 0)
			(layers "F.Cu" "F.Mask" "F.Paste")
			(net "P0V9_RETIMER_CPU1_VCC1")
		)
		(pad "2" smd circle
			(at 0.40005 0 90)
			(size 0 0)
			(layers "F.Cu" "F.Mask" "F.Paste")
			(net "GND")
		)
	)
	(footprint ""
		(layer "F.Cu")
		(at 436.100474 -19.62277 -90)
		(property "Reference" "R40"
			(at 0 0 270)
			(layer "F.SilkS")
			(hide yes)
			(effects
				(font
					(size 1.27 1.27)
				)
			)
		)
		(property "Value" ""
			(at 0 0 270)
			(layer "F.Fab")
			(effects
				(font
					(size 1.27 1.27)
				)
			)
		)
		(duplicate_pad_numbers_are_jumpers no)
		(fp_line
			(start -0.7874 0.4064)
			(end -0.7874 -0.4064)
			(stroke
				(width 0.1524)
				(type default)
			)
			(layer "F.SilkS")
		)
		(fp_line
			(start 0.7874 0.4064)
			(end -0.7874 0.4064)
			(stroke
				(width 0.1524)
				(type default)
			)
			(layer "F.SilkS")
		)
		(fp_line
			(start -0.7874 -0.4064)
			(end 0.7874 -0.4064)
			(stroke
				(width 0.1524)
				(type default)
			)
			(layer "F.SilkS")
		)
		(fp_line
			(start 0.7874 -0.4064)
			(end 0.7874 0.4064)
			(stroke
				(width 0.1524)
				(type default)
			)
			(layer "F.SilkS")
		)
		(fp_line
			(start -0.67945 0.3048)
			(end -0.67945 -0.305054)
			(stroke
				(width 0.1)
				(type default)
			)
			(layer "F.Fab")
		)
		(fp_line
			(start -0.12065 0.3048)
			(end -0.67945 0.3048)
			(stroke
				(width 0.1)
				(type default)
			)
			(layer "F.Fab")
		)
		(fp_line
			(start 0.120396 0.3048)
			(end 0.120396 0.2794)
			(stroke
				(width 0.1)
				(type default)
			)
			(layer "F.Fab")
		)
		(fp_line
			(start 0.67945 0.3048)
			(end 0.120396 0.3048)
			(stroke
				(width 0.1)
				(type default)
			)
			(layer "F.Fab")
		)
		(fp_line
			(start -0.12065 0.2794)
			(end -0.12065 0.3048)
			(stroke
				(width 0.1)
				(type default)
			)
			(layer "F.Fab")
		)
		(fp_line
			(start 0.120396 0.2794)
			(end -0.12065 0.2794)
			(stroke
				(width 0.1)
				(type default)
			)
			(layer "F.Fab")
		)
		(fp_line
			(start -0.12065 -0.2794)
			(end 0.12065 -0.2794)
			(stroke
				(width 0.1)
				(type default)
			)
			(layer "F.Fab")
		)
		(fp_line
			(start 0.12065 -0.2794)
			(end 0.12065 -0.3048)
			(stroke
				(width 0.1)
				(type default)
			)
			(layer "F.Fab")
		)
		(fp_line
			(start 0.12065 -0.3048)
			(end 0.67945 -0.3048)
			(stroke
				(width 0.1)
				(type default)
			)
			(layer "F.Fab")
		)
		(fp_line
			(start 0.67945 -0.3048)
			(end 0.67945 0.3048)
			(stroke
				(width 0.1)
				(type default)
			)
			(layer "F.Fab")
		)
		(fp_line
			(start -0.67945 -0.305054)
			(end -0.12065 -0.305054)
			(stroke
				(width 0.1)
				(type default)
			)
			(layer "F.Fab")
		)
		(fp_line
			(start -0.12065 -0.305054)
			(end -0.12065 -0.2794)
			(stroke
				(width 0.1)
				(type default)
			)
			(layer "F.Fab")
		)
		(pad "1" smd circle
			(at -0.40005 0 270)
			(size 0 0)
			(layers "F.Cu" "F.Mask" "F.Paste")
			(net "OCP_SFF_ISO_BIF1_EN")
		)
		(pad "2" smd circle
			(at 0.40005 0 270)
			(size 0 0)
			(layers "F.Cu" "F.Mask" "F.Paste")
			(net "OCP_SFF_BIF1_R_N")
		)
	)
)
